(kicad_pcb
	(version 20241229)
	(generator "pcbnew")
	(generator_version "9.0")
	(general
		(thickness 1.62)
		(legacy_teardrops no)
	)
	(paper "A4")
	(title_block
		(title "OCuLink to 10GbE adapter")
		(date "2026-02-23")
		(rev "1.1.0")
		(company "Antmicro Ltd")
		(comment 1 "www.antmicro.com")
		(comment 9 "footprints 490-494 of 510")
	)
	(layers
		(0 "F.Cu" signal)
		(4 "In1.Cu" signal)
		(6 "In2.Cu" signal)
		(8 "In3.Cu" signal)
		(10 "In4.Cu" signal)
		(12 "In5.Cu" signal)
		(14 "In6.Cu" signal)
		(2 "B.Cu" signal)
		(9 "F.Adhes" user "F.Adhesive")
		(11 "B.Adhes" user "B.Adhesive")
		(13 "F.Paste" user)
		(15 "B.Paste" user)
		(5 "F.SilkS" user "F.Silkscreen")
		(7 "B.SilkS" user "B.Silkscreen")
		(1 "F.Mask" user)
		(3 "B.Mask" user)
		(17 "Dwgs.User" user "User.Drawings")
		(19 "Cmts.User" user "User.Comments")
		(21 "Eco1.User" user "User.Eco1")
		(23 "Eco2.User" user "User.Eco2")
		(25 "Edge.Cuts" user)
		(27 "Margin" user)
		(31 "F.CrtYd" user "F.Courtyard")
		(29 "B.CrtYd" user "B.Courtyard")
		(35 "F.Fab" user)
		(33 "B.Fab" user)
	)
	(footprint "antmicro-footprints:C_Pol_EIA-D"
		(layer "B.Cu")
		(at 65.25 98.45 -90)
		(property "Reference" "C78"
			(at -1 2.45 90)
			(layer "B.SilkS")
			(effects
				(font
					(size 0.7 0.7)
					(thickness 0.15)
				)
				(justify left bottom mirror)
			)
		)
		(property "Value" "C_Pol_470u_6.3V_Vishay-TR3-D"
			(at 0 -3.4 90)
			(layer "B.Fab")
			(hide yes)
			(effects
				(font
					(size 0.7 0.7)
					(thickness 0.15)
				)
				(justify left bottom mirror)
			)
		)
		(property "Datasheet" "https://www.vishay.com/docs/40080/tr3.pdf"
			(at 0 0 90)
			(layer "B.Fab")
			(hide yes)
			(effects
				(font
					(size 1.27 1.27)
					(thickness 0.15)
				)
				(justify mirror)
			)
		)
		(property "Description" "470 µF Molded Tantalum Capacitors 6.3 V 2917 (7343 Metric) 200mOhm"
			(at 0 0 90)
			(layer "B.Fab")
			(hide yes)
			(effects
				(font
					(size 1.27 1.27)
					(thickness 0.15)
				)
				(justify mirror)
			)
		)
		(property "Val" "470u"
			(at 0 0 270)
			(unlocked yes)
			(layer "B.Fab")
			(hide yes)
			(effects
				(font
					(size 1 1)
					(thickness 0.15)
				)
				(justify mirror)
			)
		)
		(property "MPN" "TR3D477M6R3C0200"
			(at 0 0 270)
			(unlocked yes)
			(layer "B.Fab")
			(hide yes)
			(effects
				(font
					(size 1 1)
					(thickness 0.15)
				)
				(justify mirror)
			)
		)
		(property "Manufacturer" "Vishay"
			(at 0 0 270)
			(unlocked yes)
			(layer "B.Fab")
			(hide yes)
			(effects
				(font
					(size 1 1)
					(thickness 0.15)
				)
				(justify mirror)
			)
		)
		(property "License" "Apache-2.0"
			(at 0 0 270)
			(unlocked yes)
			(layer "B.Fab")
			(hide yes)
			(effects
				(font
					(size 1 1)
					(thickness 0.15)
				)
				(justify mirror)
			)
		)
		(property "Author" "Antmicro"
			(at 0 0 270)
			(unlocked yes)
			(layer "B.Fab")
			(hide yes)
			(effects
				(font
					(size 1 1)
					(thickness 0.15)
				)
				(justify mirror)
			)
		)
		(property "Voltage" "6.3V"
			(at 0 0 270)
			(unlocked yes)
			(layer "B.Fab")
			(hide yes)
			(effects
				(font
					(size 1 1)
					(thickness 0.15)
				)
				(justify mirror)
			)
		)
		(property "Dielectric" "template_dielectric"
			(at 0 0 270)
			(unlocked yes)
			(layer "B.Fab")
			(hide yes)
			(effects
				(font
					(size 1 1)
					(thickness 0.15)
				)
				(justify mirror)
			)
		)
		(sheetname "/X710-AT2 power/")
		(sheetfile "x710-at2-power.kicad_sch")
		(attr smd)
		(fp_line
			(start -3.58 2.2)
			(end 3.6 2.2)
			(stroke
				(width 0.15)
				(type solid)
			)
			(layer "B.SilkS")
		)
		(fp_line
			(start 3.6 2.2)
			(end 3.6 1.6)
			(stroke
				(width 0.15)
				(type solid)
			)
			(layer "B.SilkS")
		)
		(fp_line
			(start -4.1 2.025)
			(end -4.1 1.625)
			(stroke
				(width 0.12)
				(type solid)
			)
			(layer "B.SilkS")
		)
		(fp_line
			(start -4.3 1.825)
			(end -3.9 1.825)
			(stroke
				(width 0.12)
				(type solid)
			)
			(layer "B.SilkS")
		)
		(fp_line
			(start -3.58 1.6)
			(end -3.58 2.2)
			(stroke
				(width 0.15)
				(type solid)
			)
			(layer "B.SilkS")
		)
		(fp_line
			(start 3.6 -1.6)
			(end 3.6 -2.2)
			(stroke
				(width 0.15)
				(type solid)
			)
			(layer "B.SilkS")
		)
		(fp_line
			(start -3.58 -2.2)
			(end -3.58 -1.6)
			(stroke
				(width 0.15)
				(type solid)
			)
			(layer "B.SilkS")
		)
		(fp_line
			(start 3.6 -2.2)
			(end -3.58 -2.2)
			(stroke
				(width 0.15)
				(type solid)
			)
			(layer "B.SilkS")
		)
		(fp_line
			(start -3.775 2.4)
			(end 3.77 2.4)
			(stroke
				(width 0.05)
				(type solid)
			)
			(layer "B.CrtYd")
		)
		(fp_line
			(start -3.775 2.4)
			(end -3.775 1.5)
			(stroke
				(width 0.05)
				(type solid)
			)
			(layer "B.CrtYd")
		)
		(fp_line
			(start 3.77 2.4)
			(end 3.77 1.51)
			(stroke
				(width 0.05)
				(type solid)
			)
			(layer "B.CrtYd")
		)
		(fp_line
			(start 3.77 1.51)
			(end 4.505 1.51)
			(stroke
				(width 0.05)
				(type solid)
			)
			(layer "B.CrtYd")
		)
		(fp_line
			(start 4.505 1.51)
			(end 4.505 -1.5)
			(stroke
				(width 0.05)
				(type solid)
			)
			(layer "B.CrtYd")
		)
		(fp_line
			(start -3.775 1.5)
			(end -4.505 1.5)
			(stroke
				(width 0.05)
				(type solid)
			)
			(layer "B.CrtYd")
		)
		(fp_line
			(start -4.505 -1.51)
			(end -4.505 1.5)
			(stroke
				(width 0.05)
				(type solid)
			)
			(layer "B.CrtYd")
		)
		(fp_line
			(start -3.77 -1.51)
			(end -4.505 -1.51)
			(stroke
				(width 0.05)
				(type solid)
			)
			(layer "B.CrtYd")
		)
		(fp_line
			(start 3.77 -1.51)
			(end 3.77 -2.4)
			(stroke
				(width 0.05)
				(type solid)
			)
			(layer "B.CrtYd")
		)
		(fp_line
			(start 4.505 -1.51)
			(end 3.77 -1.51)
			(stroke
				(width 0.05)
				(type solid)
			)
			(layer "B.CrtYd")
		)
		(fp_line
			(start -3.77 -2.4)
			(end -3.77 -1.51)
			(stroke
				(width 0.05)
				(type solid)
			)
			(layer "B.CrtYd")
		)
		(fp_line
			(start 3.77 -2.4)
			(end -3.77 -2.4)
			(stroke
				(width 0.05)
				(type solid)
			)
			(layer "B.CrtYd")
		)
		(fp_rect
			(start -3.65 2.15)
			(end 3.65 -2.15)
			(stroke
				(width 0.15)
				(type solid)
			)
			(fill no)
			(layer "B.Fab")
		)
		(pad "1" smd roundrect
			(at -3.1 0 270)
			(size 2.31 2.52)
			(layers "B.Cu" "B.Mask" "B.Paste")
			(roundrect_rratio 0.1)
			(net 6 "DVDD")
			(pintype "passive")
		)
		(pad "2" smd roundrect
			(at 3.1 0 270)
			(size 2.31 2.52)
			(layers "B.Cu" "B.Mask" "B.Paste")
			(roundrect_rratio 0.1)
			(net 28 "GND")
			(pintype "passive")
		)
	)
	(footprint "antmicro-footprints:TP_SMD_0.75mm"
		(layer "B.Cu")
		(at 110.95 71.1 90)
		(property "Reference" "TP16"
			(at 0.3 0.54 180)
			(layer "B.SilkS")
			(effects
				(font
					(size 0.7 0.7)
					(thickness 0.15)
				)
				(justify right top mirror)
			)
		)
		(property "Value" "TP_0.75mm_SMD"
			(at 0 -1.2 90)
			(layer "B.Fab")
			(hide yes)
			(effects
				(font
					(size 0.7 0.7)
					(thickness 0.15)
				)
				(justify right top mirror)
			)
		)
		(property "Description" "SMT test point"
			(at 0 0 90)
			(layer "B.Fab")
			(hide yes)
			(effects
				(font
					(size 1.27 1.27)
					(thickness 0.15)
				)
				(justify mirror)
			)
		)
		(property "MPN" ""
			(at 0 0 90)
			(unlocked yes)
			(layer "B.Fab")
			(hide yes)
			(effects
				(font
					(size 1 1)
					(thickness 0.15)
				)
				(justify mirror)
			)
		)
		(property "Manufacturer" ""
			(at 0 0 90)
			(unlocked yes)
			(layer "B.Fab")
			(hide yes)
			(effects
				(font
					(size 1 1)
					(thickness 0.15)
				)
				(justify mirror)
			)
		)
		(property "Author" "Antmicro"
			(at 0 0 90)
			(unlocked yes)
			(layer "B.Fab")
			(hide yes)
			(effects
				(font
					(size 1 1)
					(thickness 0.15)
				)
				(justify mirror)
			)
		)
		(property "License" "Apache-2.0"
			(at 0 0 90)
			(unlocked yes)
			(layer "B.Fab")
			(hide yes)
			(effects
				(font
					(size 1 1)
					(thickness 0.15)
				)
				(justify mirror)
			)
		)
		(sheetname "/OCuLink/")
		(sheetfile "oculink.kicad_sch")
		(attr exclude_from_pos_files exclude_from_bom)
		(fp_circle
			(center 0 0)
			(end 0.475 0)
			(stroke
				(width 0.05)
				(type default)
			)
			(fill no)
			(layer "B.CrtYd")
		)
		(pad "1" smd circle
			(at 0 0 90)
			(size 0.75 0.75)
			(layers "B.Cu" "B.Mask")
			(net 320 "/OCuLink/~{CWAKE}_R")
			(pinfunction "1")
			(pintype "passive")
		)
	)
	(footprint "antmicro-footprints:C_0402_1005Metric"
		(layer "B.Cu")
		(at 91.225 94.6 90)
		(descr "Capacitor SMD 0402")
		(tags "capacitor SMD 0402")
		(property "Reference" "C117"
			(at 12.5 -0.462343 90)
			(layer "B.SilkS")
			(effects
				(font
					(size 0.7 0.7)
					(thickness 0.15)
				)
				(justify right top mirror)
			)
		)
		(property "Value" "C_1u_25V_0402"
			(at -1.022927 -2.155213 90)
			(layer "B.Fab")
			(hide yes)
			(effects
				(font
					(size 0.7 0.7)
					(thickness 0.15)
				)
				(justify right top mirror)
			)
		)
		(property "Datasheet" "https://www.murata.com/products/productdetail?partno=GRM155R61E105KE11%23"
			(at 0 0 90)
			(layer "B.Fab")
			(hide yes)
			(effects
				(font
					(size 1.27 1.27)
					(thickness 0.15)
				)
				(justify mirror)
			)
		)
		(property "Description" "SMD Multilayer Ceramic Capacitor, 1 µF, 25 V, 0402 [1005 Metric], ± 10%, X5R, GRM Series"
			(at 0 0 90)
			(layer "B.Fab")
			(hide yes)
			(effects
				(font
					(size 1.27 1.27)
					(thickness 0.15)
				)
				(justify mirror)
			)
		)
		(property "MPN" "GRM155R61E105KE11J"
			(at 0 0 90)
			(unlocked yes)
			(layer "B.Fab")
			(hide yes)
			(effects
				(font
					(size 1 1)
					(thickness 0.15)
				)
				(justify mirror)
			)
		)
		(property "Manufacturer" "Murata"
			(at 0 0 90)
			(unlocked yes)
			(layer "B.Fab")
			(hide yes)
			(effects
				(font
					(size 1 1)
					(thickness 0.15)
				)
				(justify mirror)
			)
		)
		(property "License" "Apache-2.0"
			(at 0 0 90)
			(unlocked yes)
			(layer "B.Fab")
			(hide yes)
			(effects
				(font
					(size 1 1)
					(thickness 0.15)
				)
				(justify mirror)
			)
		)
		(property "Author" "Antmicro"
			(at 0 0 90)
			(unlocked yes)
			(layer "B.Fab")
			(hide yes)
			(effects
				(font
					(size 1 1)
					(thickness 0.15)
				)
				(justify mirror)
			)
		)
		(property "Val" "1u"
			(at 0 0 90)
			(unlocked yes)
			(layer "B.Fab")
			(hide yes)
			(effects
				(font
					(size 1 1)
					(thickness 0.15)
				)
				(justify mirror)
			)
		)
		(property "Voltage" "25V"
			(at 0 0 90)
			(unlocked yes)
			(layer "B.Fab")
			(hide yes)
			(effects
				(font
					(size 1 1)
					(thickness 0.15)
				)
				(justify mirror)
			)
		)
		(property "Dielectric" "X5R"
			(at 0 0 90)
			(unlocked yes)
			(layer "B.Fab")
			(hide yes)
			(effects
				(font
					(size 1 1)
					(thickness 0.15)
				)
				(justify mirror)
			)
		)
		(sheetname "/X710-AT2 power/")
		(sheetfile "x710-at2-power.kicad_sch")
		(attr smd)
		(fp_rect
			(start -0.925 0.47)
			(end 0.925 -0.47)
			(stroke
				(width 0.05)
				(type default)
			)
			(fill no)
			(layer "B.CrtYd")
		)
		(fp_line
			(start 0.504 -0.248)
			(end -0.494 -0.248)
			(stroke
				(width 0.15)
				(type solid)
			)
			(layer "B.Fab")
		)
		(fp_line
			(start -0.494 -0.248)
			(end -0.494 0.25)
			(stroke
				(width 0.15)
				(type solid)
			)
			(layer "B.Fab")
		)
		(fp_line
			(start 0.504 0.25)
			(end 0.504 -0.248)
			(stroke
				(width 0.15)
				(type solid)
			)
			(layer "B.Fab")
		)
		(fp_line
			(start -0.494 0.25)
			(end 0.504 0.25)
			(stroke
				(width 0.15)
				(type solid)
			)
			(layer "B.Fab")
		)
		(pad "1" smd roundrect
			(at -0.48 0 90)
			(size 0.59 0.64)
			(layers "B.Cu" "B.Mask" "B.Paste")
			(roundrect_rratio 0.25)
			(net 28 "GND")
			(pintype "passive")
		)
		(pad "2" smd roundrect
			(at 0.48 0 90)
			(size 0.59 0.64)
			(layers "B.Cu" "B.Mask" "B.Paste")
			(roundrect_rratio 0.25)
			(net 9 "VCCD")
			(pintype "passive")
		)
	)
	(footprint "antmicro-footprints:C_0402_1005Metric"
		(layer "B.Cu")
		(at 77.48 106.05 -90)
		(descr "Capacitor SMD 0402")
		(tags "capacitor SMD 0402")
		(property "Reference" "C142"
			(at 8.99 -0.09 90)
			(layer "B.SilkS")
			(effects
				(font
					(size 0.7 0.7)
					(thickness 0.15)
				)
				(justify left bottom mirror)
			)
		)
		(property "Value" "C_1u_25V_0402"
			(at -1.022927 -2.155213 90)
			(layer "B.Fab")
			(hide yes)
			(effects
				(font
					(size 0.7 0.7)
					(thickness 0.15)
				)
				(justify left bottom mirror)
			)
		)
		(property "Datasheet" "https://www.murata.com/products/productdetail?partno=GRM155R61E105KE11%23"
			(at 0 0 90)
			(layer "B.Fab")
			(hide yes)
			(effects
				(font
					(size 1.27 1.27)
					(thickness 0.15)
				)
				(justify mirror)
			)
		)
		(property "Description" "SMD Multilayer Ceramic Capacitor, 1 µF, 25 V, 0402 [1005 Metric], ± 10%, X5R, GRM Series"
			(at 0 0 90)
			(layer "B.Fab")
			(hide yes)
			(effects
				(font
					(size 1.27 1.27)
					(thickness 0.15)
				)
				(justify mirror)
			)
		)
		(property "MPN" "GRM155R61E105KE11J"
			(at 0 0 270)
			(unlocked yes)
			(layer "B.Fab")
			(hide yes)
			(effects
				(font
					(size 1 1)
					(thickness 0.15)
				)
				(justify mirror)
			)
		)
		(property "Manufacturer" "Murata"
			(at 0 0 270)
			(unlocked yes)
			(layer "B.Fab")
			(hide yes)
			(effects
				(font
					(size 1 1)
					(thickness 0.15)
				)
				(justify mirror)
			)
		)
		(property "License" "Apache-2.0"
			(at 0 0 270)
			(unlocked yes)
			(layer "B.Fab")
			(hide yes)
			(effects
				(font
					(size 1 1)
					(thickness 0.15)
				)
				(justify mirror)
			)
		)
		(property "Author" "Antmicro"
			(at 0 0 270)
			(unlocked yes)
			(layer "B.Fab")
			(hide yes)
			(effects
				(font
					(size 1 1)
					(thickness 0.15)
				)
				(justify mirror)
			)
		)
		(property "Val" "1u"
			(at 0 0 270)
			(unlocked yes)
			(layer "B.Fab")
			(hide yes)
			(effects
				(font
					(size 1 1)
					(thickness 0.15)
				)
				(justify mirror)
			)
		)
		(property "Voltage" "25V"
			(at 0 0 270)
			(unlocked yes)
			(layer "B.Fab")
			(hide yes)
			(effects
				(font
					(size 1 1)
					(thickness 0.15)
				)
				(justify mirror)
			)
		)
		(property "Dielectric" "X5R"
			(at 0 0 270)
			(unlocked yes)
			(layer "B.Fab")
			(hide yes)
			(effects
				(font
					(size 1 1)
					(thickness 0.15)
				)
				(justify mirror)
			)
		)
		(sheetname "/X710-AT2 power/")
		(sheetfile "x710-at2-power.kicad_sch")
		(attr smd)
		(fp_rect
			(start -0.925 0.47)
			(end 0.925 -0.47)
			(stroke
				(width 0.05)
				(type default)
			)
			(fill no)
			(layer "B.CrtYd")
		)
		(fp_line
			(start -0.494 0.25)
			(end 0.504 0.25)
			(stroke
				(width 0.15)
				(type solid)
			)
			(layer "B.Fab")
		)
		(fp_line
			(start 0.504 0.25)
			(end 0.504 -0.248)
			(stroke
				(width 0.15)
				(type solid)
			)
			(layer "B.Fab")
		)
		(fp_line
			(start -0.494 -0.248)
			(end -0.494 0.25)
			(stroke
				(width 0.15)
				(type solid)
			)
			(layer "B.Fab")
		)
		(fp_line
			(start 0.504 -0.248)
			(end -0.494 -0.248)
			(stroke
				(width 0.15)
				(type solid)
			)
			(layer "B.Fab")
		)
		(pad "1" smd roundrect
			(at -0.48 0 270)
			(size 0.59 0.64)
			(layers "B.Cu" "B.Mask" "B.Paste")
			(roundrect_rratio 0.25)
			(net 28 "GND")
			(pintype "passive")
		)
		(pad "2" smd roundrect
			(at 0.48 0 270)
			(size 0.59 0.64)
			(layers "B.Cu" "B.Mask" "B.Paste")
			(roundrect_rratio 0.25)
			(net 10 "AVDDH")
			(pintype "passive")
		)
	)
	(footprint "antmicro-footprints:R_0402_1005Metric"
		(layer "B.Cu")
		(at 72.48 145.34 90)
		(descr "Resistor SMD 0402")
		(tags "resistor SMD 0402")
		(property "Reference" "R38"
			(at 0.76 -0.37 90)
			(layer "B.SilkS")
			(effects
				(font
					(size 0.7 0.7)
					(thickness 0.15)
				)
				(justify right top mirror)
			)
		)
		(property "Value" "R_220R_0402"
			(at -1.011843 -1.772046 90)
			(layer "B.Fab")
			(hide yes)
			(effects
				(font
					(size 0.7 0.7)
					(thickness 0.15)
				)
				(justify right top mirror)
			)
		)
		(property "Datasheet" "https://www.bourns.com/docs/product-datasheets/cr.pdf"
			(at 0 0 90)
			(layer "B.Fab")
			(hide yes)
			(effects
				(font
					(size 1.27 1.27)
					(thickness 0.15)
				)
				(justify mirror)
			)
		)
		(property "Description" "SMD Chip Resistor, 220 ohm, ± 1%, 62.5 mW, 0402 [1005 Metric], Thick Film, General Purpose"
			(at 0 0 90)
			(layer "B.Fab")
			(hide yes)
			(effects
				(font
					(size 1.27 1.27)
					(thickness 0.15)
				)
				(justify mirror)
			)
		)
		(property "MPN" "CR0402-FX-2200GLF"
			(at 0 0 90)
			(unlocked yes)
			(layer "B.Fab")
			(hide yes)
			(effects
				(font
					(size 1 1)
					(thickness 0.15)
				)
				(justify mirror)
			)
		)
		(property "Manufacturer" "Bourns"
			(at 0 0 90)
			(unlocked yes)
			(layer "B.Fab")
			(hide yes)
			(effects
				(font
					(size 1 1)
					(thickness 0.15)
				)
				(justify mirror)
			)
		)
		(property "License" "Apache-2.0"
			(at 0 0 90)
			(unlocked yes)
			(layer "B.Fab")
			(hide yes)
			(effects
				(font
					(size 1 1)
					(thickness 0.15)
				)
				(justify mirror)
			)
		)
		(property "Author" "Antmicro"
			(at 0 0 90)
			(unlocked yes)
			(layer "B.Fab")
			(hide yes)
			(effects
				(font
					(size 1 1)
					(thickness 0.15)
				)
				(justify mirror)
			)
		)
		(property "Val" "220R"
			(at 0 0 90)
			(unlocked yes)
			(layer "B.Fab")
			(hide yes)
			(effects
				(font
					(size 1 1)
					(thickness 0.15)
				)
				(justify mirror)
			)
		)
		(property "Tolerance" "1%"
			(at 0 0 90)
			(unlocked yes)
			(layer "B.Fab")
			(hide yes)
			(effects
				(font
					(size 1 1)
					(thickness 0.15)
				)
				(justify mirror)
			)
		)
		(sheetname "/2xRJ45/")
		(sheetfile "2xrj45.kicad_sch")
		(attr smd)
		(fp_rect
			(start -0.925 0.47)
			(end 0.925 -0.47)
			(stroke
				(width 0.05)
				(type default)
			)
			(fill no)
			(layer "B.CrtYd")
		)
		(fp_rect
			(start -0.5 0.25)
			(end 0.5 -0.25)
			(stroke
				(width 0.15)
				(type solid)
			)
			(fill no)
			(layer "B.Fab")
		)
		(pad "1" smd roundrect
			(at -0.48 0 90)
			(size 0.59 0.64)
			(layers "B.Cu" "B.Mask" "B.Paste")
			(roundrect_rratio 0.25)
			(net 54 "Net-(J3-LED_GRN-)")
			(pintype "passive")
		)
		(pad "2" smd roundrect
			(at 0.48 0 90)
			(size 0.59 0.64)
			(layers "B.Cu" "B.Mask" "B.Paste")
			(roundrect_rratio 0.25)
			(net 82 "/2xRJ45/~{P0_LED_ACT}")
			(pintype "passive")
		)
	)
)
